(kicad_pcb
	(version 20260206)
	(generator "pcbnew")
	(generator_version "10.0")
	(general
		(thickness 1.6)
		(legacy_teardrops no)
	)
	(paper "A4")
	(title_block
		(title "03242023_DA0F0TMBIJ0_F0T_Motherboard_J_brd_V01_OCP.brd")
		(comment 1 "Grand Teton / footprints 4597-4603 of 6105")
	)
	(layers
		(0 "F.Cu" signal "TOP")
		(4 "In1.Cu" signal "GND")
		(6 "In2.Cu" signal "IN1")
		(8 "In3.Cu" signal "GND1")
		(10 "In4.Cu" signal "IN2")
		(12 "In5.Cu" signal "GND2")
		(14 "In6.Cu" signal "IN3")
		(16 "In7.Cu" signal "GND3")
		(18 "In8.Cu" signal "VCC")
		(20 "In9.Cu" signal "VCC1")
		(22 "In10.Cu" signal "GND4")
		(24 "In11.Cu" signal "IN4")
		(26 "In12.Cu" signal "GND5")
		(28 "In13.Cu" signal "IN5")
		(30 "In14.Cu" signal "GND6")
		(32 "In15.Cu" signal "IN6")
		(34 "In16.Cu" signal "GND7")
		(2 "B.Cu" signal "BOTTOM")
		(9 "F.Adhes" user "F.Adhesive")
		(11 "B.Adhes" user "B.Adhesive")
		(13 "F.Paste" user "Package Geometry/Pastemask Top")
		(15 "B.Paste" user "Package Geometry/Pastemask Bottom")
		(5 "F.SilkS" user "Ref Des/Silkscreen Top")
		(7 "B.SilkS" user "Ref Des/Silkscreen Bottom")
		(1 "F.Mask" user "Board Geometry/Soldermask Top")
		(3 "B.Mask" user "Board Geometry/Soldermask Bottom")
		(17 "Dwgs.User" user "User.Drawings")
		(19 "Cmts.User" user "User.Comments")
		(21 "Eco1.User" user "User.Eco1")
		(23 "Eco2.User" user "User.Eco2")
		(25 "Edge.Cuts" user "Board Geometry/Outline")
		(27 "Margin" user)
		(31 "F.CrtYd" user "Package Geometry/Place Bound Top")
		(29 "B.CrtYd" user "Package Geometry/Place Bound Bottom")
		(35 "F.Fab" user "Ref Des/Assembly Top")
		(33 "B.Fab" user "Ref Des/Assembly Bottom")
	)
	(footprint ""
		(layer "B.Cu")
		(at 55.695088 -193.39179 90)
		(property "Reference" "R157"
			(at 0 0 90)
			(layer "B.SilkS")
			(hide yes)
			(effects
				(font
					(size 1.27 1.27)
				)
				(justify mirror)
			)
		)
		(property "Value" ""
			(at 0 0 90)
			(layer "B.Fab")
			(effects
				(font
					(size 1.27 1.27)
				)
				(justify mirror)
			)
		)
		(duplicate_pad_numbers_are_jumpers no)
		(fp_line
			(start 0.7874 -0.4064)
			(end -0.7874 -0.4064)
			(stroke
				(width 0.1524)
				(type default)
			)
			(layer "B.SilkS")
		)
		(fp_line
			(start -0.7874 -0.4064)
			(end -0.7874 0.4064)
			(stroke
				(width 0.1524)
				(type default)
			)
			(layer "B.SilkS")
		)
		(fp_line
			(start 0.7874 0.4064)
			(end 0.7874 -0.4064)
			(stroke
				(width 0.1524)
				(type default)
			)
			(layer "B.SilkS")
		)
		(fp_line
			(start -0.7874 0.4064)
			(end 0.7874 0.4064)
			(stroke
				(width 0.1524)
				(type default)
			)
			(layer "B.SilkS")
		)
		(fp_line
			(start 0.67945 -0.305054)
			(end 0.12065 -0.305054)
			(stroke
				(width 0.1)
				(type default)
			)
			(layer "B.Fab")
		)
		(fp_line
			(start 0.12065 -0.305054)
			(end 0.12065 -0.2794)
			(stroke
				(width 0.1)
				(type default)
			)
			(layer "B.Fab")
		)
		(fp_line
			(start -0.12065 -0.3048)
			(end -0.67945 -0.3048)
			(stroke
				(width 0.1)
				(type default)
			)
			(layer "B.Fab")
		)
		(fp_line
			(start -0.67945 -0.3048)
			(end -0.67945 0.3048)
			(stroke
				(width 0.1)
				(type default)
			)
			(layer "B.Fab")
		)
		(fp_line
			(start 0.12065 -0.2794)
			(end -0.12065 -0.2794)
			(stroke
				(width 0.1)
				(type default)
			)
			(layer "B.Fab")
		)
		(fp_line
			(start -0.12065 -0.2794)
			(end -0.12065 -0.3048)
			(stroke
				(width 0.1)
				(type default)
			)
			(layer "B.Fab")
		)
		(fp_line
			(start 0.12065 0.2794)
			(end 0.12065 0.3048)
			(stroke
				(width 0.1)
				(type default)
			)
			(layer "B.Fab")
		)
		(fp_line
			(start -0.120396 0.2794)
			(end 0.12065 0.2794)
			(stroke
				(width 0.1)
				(type default)
			)
			(layer "B.Fab")
		)
		(fp_line
			(start 0.67945 0.3048)
			(end 0.67945 -0.305054)
			(stroke
				(width 0.1)
				(type default)
			)
			(layer "B.Fab")
		)
		(fp_line
			(start 0.12065 0.3048)
			(end 0.67945 0.3048)
			(stroke
				(width 0.1)
				(type default)
			)
			(layer "B.Fab")
		)
		(fp_line
			(start -0.120396 0.3048)
			(end -0.120396 0.2794)
			(stroke
				(width 0.1)
				(type default)
			)
			(layer "B.Fab")
		)
		(fp_line
			(start -0.67945 0.3048)
			(end -0.120396 0.3048)
			(stroke
				(width 0.1)
				(type default)
			)
			(layer "B.Fab")
		)
		(pad "1" smd circle
			(at 0.40005 0 270)
			(size 0 0)
			(layers "B.Cu" "B.Mask" "B.Paste")
			(net "RST_CPU1_BUF_R_N")
		)
		(pad "2" smd circle
			(at -0.40005 0 270)
			(size 0 0)
			(layers "B.Cu" "B.Mask" "B.Paste")
			(net "PVNN_TERM_CPU1")
		)
	)
	(footprint ""
		(layer "B.Cu")
		(at 440.383676 -15.656306)
		(property "Reference" "C1234"
			(at 0 0 0)
			(layer "B.SilkS")
			(hide yes)
			(effects
				(font
					(size 1.27 1.27)
				)
				(justify mirror)
			)
		)
		(property "Value" ""
			(at 0 0 0)
			(layer "B.Fab")
			(effects
				(font
					(size 1.27 1.27)
				)
				(justify mirror)
			)
		)
		(duplicate_pad_numbers_are_jumpers no)
		(fp_line
			(start -0.7874 -0.4064)
			(end -0.7874 0.4064)
			(stroke
				(width 0.1524)
				(type default)
			)
			(layer "B.SilkS")
		)
		(fp_line
			(start -0.7874 0.4064)
			(end 0.7874 0.4064)
			(stroke
				(width 0.1524)
				(type default)
			)
			(layer "B.SilkS")
		)
		(fp_line
			(start 0.7874 -0.4064)
			(end -0.7874 -0.4064)
			(stroke
				(width 0.1524)
				(type default)
			)
			(layer "B.SilkS")
		)
		(fp_line
			(start 0.7874 0.4064)
			(end 0.7874 -0.4064)
			(stroke
				(width 0.1524)
				(type default)
			)
			(layer "B.SilkS")
		)
		(fp_line
			(start -0.67945 -0.3048)
			(end -0.67945 0.3048)
			(stroke
				(width 0.1)
				(type default)
			)
			(layer "B.Fab")
		)
		(fp_line
			(start -0.67945 0.3048)
			(end -0.120396 0.3048)
			(stroke
				(width 0.1)
				(type default)
			)
			(layer "B.Fab")
		)
		(fp_line
			(start -0.12065 -0.3048)
			(end -0.67945 -0.3048)
			(stroke
				(width 0.1)
				(type default)
			)
			(layer "B.Fab")
		)
		(fp_line
			(start -0.12065 -0.2794)
			(end -0.12065 -0.3048)
			(stroke
				(width 0.1)
				(type default)
			)
			(layer "B.Fab")
		)
		(fp_line
			(start -0.120396 0.2794)
			(end 0.12065 0.2794)
			(stroke
				(width 0.1)
				(type default)
			)
			(layer "B.Fab")
		)
		(fp_line
			(start -0.120396 0.3048)
			(end -0.120396 0.2794)
			(stroke
				(width 0.1)
				(type default)
			)
			(layer "B.Fab")
		)
		(fp_line
			(start 0.12065 -0.305054)
			(end 0.12065 -0.2794)
			(stroke
				(width 0.1)
				(type default)
			)
			(layer "B.Fab")
		)
		(fp_line
			(start 0.12065 -0.2794)
			(end -0.12065 -0.2794)
			(stroke
				(width 0.1)
				(type default)
			)
			(layer "B.Fab")
		)
		(fp_line
			(start 0.12065 0.2794)
			(end 0.12065 0.3048)
			(stroke
				(width 0.1)
				(type default)
			)
			(layer "B.Fab")
		)
		(fp_line
			(start 0.12065 0.3048)
			(end 0.67945 0.3048)
			(stroke
				(width 0.1)
				(type default)
			)
			(layer "B.Fab")
		)
		(fp_line
			(start 0.67945 -0.305054)
			(end 0.12065 -0.305054)
			(stroke
				(width 0.1)
				(type default)
			)
			(layer "B.Fab")
		)
		(fp_line
			(start 0.67945 0.3048)
			(end 0.67945 -0.305054)
			(stroke
				(width 0.1)
				(type default)
			)
			(layer "B.Fab")
		)
		(pad "1" smd circle
			(at 0.40005 0 180)
			(size 0 0)
			(layers "B.Cu" "B.Mask" "B.Paste")
			(net "P12V_OCP_SFF")
		)
		(pad "2" smd circle
			(at -0.40005 0 180)
			(size 0 0)
			(layers "B.Cu" "B.Mask" "B.Paste")
			(net "GND")
		)
	)
	(footprint ""
		(layer "B.Cu")
		(at 213.58098 -318.107568)
		(property "Reference" "R73"
			(at 0 0 0)
			(layer "B.SilkS")
			(hide yes)
			(effects
				(font
					(size 1.27 1.27)
				)
				(justify mirror)
			)
		)
		(property "Value" ""
			(at 0 0 0)
			(layer "B.Fab")
			(effects
				(font
					(size 1.27 1.27)
				)
				(justify mirror)
			)
		)
		(duplicate_pad_numbers_are_jumpers no)
		(fp_line
			(start -0.7874 -0.4064)
			(end -0.7874 0.4064)
			(stroke
				(width 0.1524)
				(type default)
			)
			(layer "B.SilkS")
		)
		(fp_line
			(start -0.7874 0.4064)
			(end 0.7874 0.4064)
			(stroke
				(width 0.1524)
				(type default)
			)
			(layer "B.SilkS")
		)
		(fp_line
			(start 0.7874 -0.4064)
			(end -0.7874 -0.4064)
			(stroke
				(width 0.1524)
				(type default)
			)
			(layer "B.SilkS")
		)
		(fp_line
			(start 0.7874 0.4064)
			(end 0.7874 -0.4064)
			(stroke
				(width 0.1524)
				(type default)
			)
			(layer "B.SilkS")
		)
		(fp_line
			(start -0.67945 -0.3048)
			(end -0.67945 0.3048)
			(stroke
				(width 0.1)
				(type default)
			)
			(layer "B.Fab")
		)
		(fp_line
			(start -0.67945 0.3048)
			(end -0.120396 0.3048)
			(stroke
				(width 0.1)
				(type default)
			)
			(layer "B.Fab")
		)
		(fp_line
			(start -0.12065 -0.3048)
			(end -0.67945 -0.3048)
			(stroke
				(width 0.1)
				(type default)
			)
			(layer "B.Fab")
		)
		(fp_line
			(start -0.12065 -0.2794)
			(end -0.12065 -0.3048)
			(stroke
				(width 0.1)
				(type default)
			)
			(layer "B.Fab")
		)
		(fp_line
			(start -0.120396 0.2794)
			(end 0.12065 0.2794)
			(stroke
				(width 0.1)
				(type default)
			)
			(layer "B.Fab")
		)
		(fp_line
			(start -0.120396 0.3048)
			(end -0.120396 0.2794)
			(stroke
				(width 0.1)
				(type default)
			)
			(layer "B.Fab")
		)
		(fp_line
			(start 0.12065 -0.305054)
			(end 0.12065 -0.2794)
			(stroke
				(width 0.1)
				(type default)
			)
			(layer "B.Fab")
		)
		(fp_line
			(start 0.12065 -0.2794)
			(end -0.12065 -0.2794)
			(stroke
				(width 0.1)
				(type default)
			)
			(layer "B.Fab")
		)
		(fp_line
			(start 0.12065 0.2794)
			(end 0.12065 0.3048)
			(stroke
				(width 0.1)
				(type default)
			)
			(layer "B.Fab")
		)
		(fp_line
			(start 0.12065 0.3048)
			(end 0.67945 0.3048)
			(stroke
				(width 0.1)
				(type default)
			)
			(layer "B.Fab")
		)
		(fp_line
			(start 0.67945 -0.305054)
			(end 0.12065 -0.305054)
			(stroke
				(width 0.1)
				(type default)
			)
			(layer "B.Fab")
		)
		(fp_line
			(start 0.67945 0.3048)
			(end 0.67945 -0.305054)
			(stroke
				(width 0.1)
				(type default)
			)
			(layer "B.Fab")
		)
		(pad "1" smd circle
			(at 0.40005 0 180)
			(size 0 0)
			(layers "B.Cu" "B.Mask" "B.Paste")
			(net "PD_CHH_CPU1_DIMM1_SAA")
		)
		(pad "2" smd circle
			(at -0.40005 0 180)
			(size 0 0)
			(layers "B.Cu" "B.Mask" "B.Paste")
			(net "GND")
		)
	)
	(footprint ""
		(layer "B.Cu")
		(at 128.85674 -18.539968 -90)
		(property "Reference" "R4279"
			(at 0 0 90)
			(layer "B.SilkS")
			(hide yes)
			(effects
				(font
					(size 1.27 1.27)
				)
				(justify mirror)
			)
		)
		(property "Value" ""
			(at 0 0 90)
			(layer "B.Fab")
			(effects
				(font
					(size 1.27 1.27)
				)
				(justify mirror)
			)
		)
		(duplicate_pad_numbers_are_jumpers no)
		(fp_line
			(start -0.7874 0.4064)
			(end 0.7874 0.4064)
			(stroke
				(width 0.1524)
				(type default)
			)
			(layer "B.SilkS")
		)
		(fp_line
			(start 0.7874 0.4064)
			(end 0.7874 -0.4064)
			(stroke
				(width 0.1524)
				(type default)
			)
			(layer "B.SilkS")
		)
		(fp_line
			(start -0.7874 -0.4064)
			(end -0.7874 0.4064)
			(stroke
				(width 0.1524)
				(type default)
			)
			(layer "B.SilkS")
		)
		(fp_line
			(start 0.7874 -0.4064)
			(end -0.7874 -0.4064)
			(stroke
				(width 0.1524)
				(type default)
			)
			(layer "B.SilkS")
		)
		(fp_line
			(start -0.67945 0.3048)
			(end -0.120396 0.3048)
			(stroke
				(width 0.1)
				(type default)
			)
			(layer "B.Fab")
		)
		(fp_line
			(start -0.120396 0.3048)
			(end -0.120396 0.2794)
			(stroke
				(width 0.1)
				(type default)
			)
			(layer "B.Fab")
		)
		(fp_line
			(start 0.12065 0.3048)
			(end 0.67945 0.3048)
			(stroke
				(width 0.1)
				(type default)
			)
			(layer "B.Fab")
		)
		(fp_line
			(start 0.67945 0.3048)
			(end 0.67945 -0.305054)
			(stroke
				(width 0.1)
				(type default)
			)
			(layer "B.Fab")
		)
		(fp_line
			(start -0.120396 0.2794)
			(end 0.12065 0.2794)
			(stroke
				(width 0.1)
				(type default)
			)
			(layer "B.Fab")
		)
		(fp_line
			(start 0.12065 0.2794)
			(end 0.12065 0.3048)
			(stroke
				(width 0.1)
				(type default)
			)
			(layer "B.Fab")
		)
		(fp_line
			(start -0.12065 -0.2794)
			(end -0.12065 -0.3048)
			(stroke
				(width 0.1)
				(type default)
			)
			(layer "B.Fab")
		)
		(fp_line
			(start 0.12065 -0.2794)
			(end -0.12065 -0.2794)
			(stroke
				(width 0.1)
				(type default)
			)
			(layer "B.Fab")
		)
		(fp_line
			(start -0.67945 -0.3048)
			(end -0.67945 0.3048)
			(stroke
				(width 0.1)
				(type default)
			)
			(layer "B.Fab")
		)
		(fp_line
			(start -0.12065 -0.3048)
			(end -0.67945 -0.3048)
			(stroke
				(width 0.1)
				(type default)
			)
			(layer "B.Fab")
		)
		(fp_line
			(start 0.12065 -0.305054)
			(end 0.12065 -0.2794)
			(stroke
				(width 0.1)
				(type default)
			)
			(layer "B.Fab")
		)
		(fp_line
			(start 0.67945 -0.305054)
			(end 0.12065 -0.305054)
			(stroke
				(width 0.1)
				(type default)
			)
			(layer "B.Fab")
		)
		(pad "1" smd circle
			(at 0.40005 0 90)
			(size 0 0)
			(layers "B.Cu" "B.Mask" "B.Paste")
			(net "P3V3_AUX")
		)
		(pad "2" smd circle
			(at -0.40005 0 90)
			(size 0 0)
			(layers "B.Cu" "B.Mask" "B.Paste")
			(net "FM_USB3_1_FGA")
		)
	)
	(footprint ""
		(layer "B.Cu")
		(at 170.555666 -116.975382)
		(property "Reference" "C1910"
			(at 0 0 0)
			(layer "B.SilkS")
			(hide yes)
			(effects
				(font
					(size 1.27 1.27)
				)
				(justify mirror)
			)
		)
		(property "Value" ""
			(at 0 0 0)
			(layer "B.Fab")
			(effects
				(font
					(size 1.27 1.27)
				)
				(justify mirror)
			)
		)
		(duplicate_pad_numbers_are_jumpers no)
		(fp_line
			(start -0.69215 -0.2921)
			(end -0.69215 0.2921)
			(stroke
				(width 0.1524)
				(type default)
			)
			(layer "B.SilkS")
		)
		(fp_line
			(start -0.69215 0.2921)
			(end 0.69215 0.2921)
			(stroke
				(width 0.1524)
				(type default)
			)
			(layer "B.SilkS")
		)
		(fp_line
			(start 0.69215 -0.2921)
			(end -0.69215 -0.2921)
			(stroke
				(width 0.1524)
				(type default)
			)
			(layer "B.SilkS")
		)
		(fp_line
			(start 0.69215 0.2921)
			(end 0.69215 -0.2921)
			(stroke
				(width 0.1524)
				(type default)
			)
			(layer "B.SilkS")
		)
		(fp_line
			(start -0.51435 -0.2794)
			(end -0.51435 0.2794)
			(stroke
				(width 0.1)
				(type default)
			)
			(layer "B.Fab")
		)
		(fp_line
			(start -0.51435 0.2794)
			(end 0.51435 0.2794)
			(stroke
				(width 0.1)
				(type default)
			)
			(layer "B.Fab")
		)
		(fp_line
			(start 0.51435 -0.2794)
			(end -0.51435 -0.2794)
			(stroke
				(width 0.1)
				(type default)
			)
			(layer "B.Fab")
		)
		(fp_line
			(start 0.51435 0.2794)
			(end 0.51435 -0.2794)
			(stroke
				(width 0.1)
				(type default)
			)
			(layer "B.Fab")
		)
		(pad "1" smd circle
			(at 0.40005 0 180)
			(size 0 0)
			(layers "B.Cu" "B.Mask" "B.Paste")
			(net "P3V3_AUX_FPGA_VCCIO0")
		)
		(pad "2" smd circle
			(at -0.40005 0 180)
			(size 0 0)
			(layers "B.Cu" "B.Mask" "B.Paste")
			(net "GND")
		)
		(zone
			(layer "B.Cu")
			(hatch none 0.5)
			(connect_pads
				(clearance 0)
			)
			(min_thickness 0.25)
			(keepout
				(tracks not_allowed)
				(vias allowed)
				(pads allowed)
				(copperpour not_allowed)
				(footprints allowed)
			)
			(placement
				(enabled no)
				(sheetname "")
			)
			(fill
				(thermal_gap 0.5)
				(thermal_bridge_width 0.5)
				(island_removal_mode 0)
			)
			(polygon
				(pts
					(xy 170.746166 -116.887752) (xy 170.654726 -116.829586) (xy 170.455336 -116.829586) (xy 170.365166 -116.887752)
					(xy 170.365166 -117.063012) (xy 170.455336 -117.121432) (xy 170.654726 -117.121432) (xy 170.746166 -117.063266)
				)
			)
		)
	)
	(footprint ""
		(layer "B.Cu")
		(at 88.401398 -184.01665 90)
		(property "Reference" "R1001"
			(at 0 0 90)
			(layer "B.SilkS")
			(hide yes)
			(effects
				(font
					(size 1.27 1.27)
				)
				(justify mirror)
			)
		)
		(property "Value" ""
			(at 0 0 90)
			(layer "B.Fab")
			(effects
				(font
					(size 1.27 1.27)
				)
				(justify mirror)
			)
		)
		(duplicate_pad_numbers_are_jumpers no)
		(fp_line
			(start 0.7874 -0.4064)
			(end -0.7874 -0.4064)
			(stroke
				(width 0.1524)
				(type default)
			)
			(layer "B.SilkS")
		)
		(fp_line
			(start -0.7874 -0.4064)
			(end -0.7874 0.4064)
			(stroke
				(width 0.1524)
				(type default)
			)
			(layer "B.SilkS")
		)
		(fp_line
			(start 0.7874 0.4064)
			(end 0.7874 -0.4064)
			(stroke
				(width 0.1524)
				(type default)
			)
			(layer "B.SilkS")
		)
		(fp_line
			(start -0.7874 0.4064)
			(end 0.7874 0.4064)
			(stroke
				(width 0.1524)
				(type default)
			)
			(layer "B.SilkS")
		)
		(fp_line
			(start 0.67945 -0.305054)
			(end 0.12065 -0.305054)
			(stroke
				(width 0.1)
				(type default)
			)
			(layer "B.Fab")
		)
		(fp_line
			(start 0.12065 -0.305054)
			(end 0.12065 -0.2794)
			(stroke
				(width 0.1)
				(type default)
			)
			(layer "B.Fab")
		)
		(fp_line
			(start -0.12065 -0.3048)
			(end -0.67945 -0.3048)
			(stroke
				(width 0.1)
				(type default)
			)
			(layer "B.Fab")
		)
		(fp_line
			(start -0.67945 -0.3048)
			(end -0.67945 0.3048)
			(stroke
				(width 0.1)
				(type default)
			)
			(layer "B.Fab")
		)
		(fp_line
			(start 0.12065 -0.2794)
			(end -0.12065 -0.2794)
			(stroke
				(width 0.1)
				(type default)
			)
			(layer "B.Fab")
		)
		(fp_line
			(start -0.12065 -0.2794)
			(end -0.12065 -0.3048)
			(stroke
				(width 0.1)
				(type default)
			)
			(layer "B.Fab")
		)
		(fp_line
			(start 0.12065 0.2794)
			(end 0.12065 0.3048)
			(stroke
				(width 0.1)
				(type default)
			)
			(layer "B.Fab")
		)
		(fp_line
			(start -0.120396 0.2794)
			(end 0.12065 0.2794)
			(stroke
				(width 0.1)
				(type default)
			)
			(layer "B.Fab")
		)
		(fp_line
			(start 0.67945 0.3048)
			(end 0.67945 -0.305054)
			(stroke
				(width 0.1)
				(type default)
			)
			(layer "B.Fab")
		)
		(fp_line
			(start 0.12065 0.3048)
			(end 0.67945 0.3048)
			(stroke
				(width 0.1)
				(type default)
			)
			(layer "B.Fab")
		)
		(fp_line
			(start -0.120396 0.3048)
			(end -0.120396 0.2794)
			(stroke
				(width 0.1)
				(type default)
			)
			(layer "B.Fab")
		)
		(fp_line
			(start -0.67945 0.3048)
			(end -0.120396 0.3048)
			(stroke
				(width 0.1)
				(type default)
			)
			(layer "B.Fab")
		)
		(pad "1" smd circle
			(at 0.40005 0 270)
			(size 0 0)
			(layers "B.Cu" "B.Mask" "B.Paste")
			(net "P3V3")
		)
		(pad "2" smd circle
			(at -0.40005 0 270)
			(size 0 0)
			(layers "B.Cu" "B.Mask" "B.Paste")
			(net "FM_SMB_PEHPCPU1_PCIE_ALERT_R_N")
		)
	)
	(footprint ""
		(layer "B.Cu")
		(at 64.904112 -258.472686 -90)
		(property "Reference" "C470"
			(at 0 0 90)
			(layer "B.SilkS")
			(hide yes)
			(effects
				(font
					(size 1.27 1.27)
				)
				(justify mirror)
			)
		)
		(property "Value" ""
			(at 0 0 90)
			(layer "B.Fab")
			(effects
				(font
					(size 1.27 1.27)
				)
				(justify mirror)
			)
		)
		(duplicate_pad_numbers_are_jumpers no)
		(fp_line
			(start -1.524 0.762)
			(end 1.524 0.762)
			(stroke
				(width 0.1524)
				(type default)
			)
			(layer "B.SilkS")
		)
		(fp_line
			(start 1.524 0.762)
			(end 1.524 -0.762)
			(stroke
				(width 0.1524)
				(type default)
			)
			(layer "B.SilkS")
		)
		(fp_line
			(start -1.524 -0.762)
			(end -1.524 0.762)
			(stroke
				(width 0.1524)
				(type default)
			)
			(layer "B.SilkS")
		)
		(fp_line
			(start 1.524 -0.762)
			(end -1.524 -0.762)
			(stroke
				(width 0.1524)
				(type default)
			)
			(layer "B.SilkS")
		)
		(fp_line
			(start -1.1049 0.724916)
			(end -1.1049 -0.724916)
			(stroke
				(width 0.1)
				(type default)
			)
			(layer "B.Fab")
		)
		(fp_line
			(start 1.1049 0.724916)
			(end -1.1049 0.724916)
			(stroke
				(width 0.1)
				(type default)
			)
			(layer "B.Fab")
		)
		(fp_line
			(start -1.1049 -0.724916)
			(end 1.1049 -0.724916)
			(stroke
				(width 0.1)
				(type default)
			)
			(layer "B.Fab")
		)
		(fp_line
			(start 1.1049 -0.724916)
			(end 1.1049 0.724916)
			(stroke
				(width 0.1)
				(type default)
			)
			(layer "B.Fab")
		)
		(pad "1" smd rect
			(at 0.889 0 270)
			(size 1.016 1.27)
			(layers "B.Cu" "B.Mask" "B.Paste")
			(net "PVCCFA_EHV_FIVRA_CPU1")
		)
		(pad "2" smd rect
			(at -0.889 0 270)
			(size 1.016 1.27)
			(layers "B.Cu" "B.Mask" "B.Paste")
			(net "GND")
		)
	)
)
